(kicad_pcb
	(version 20260206)
	(generator "pcbnew")
	(generator_version "10.0")
	(general
		(thickness 1.6)
		(legacy_teardrops no)
	)
	(paper "A4")
	(title_block
		(title "timecard-production-celestica-r4006 — R4006-B0001-02_R01.brd")
		(comment 1 "Time Appliance Project (Time Card) / footprints 223-228 of 1113")
	)
	(layers
		(0 "F.Cu" signal "TOP")
		(4 "In1.Cu" signal "L02_GND1")
		(6 "In2.Cu" signal "L03_SIG1")
		(8 "In3.Cu" signal "L04_GND2")
		(10 "In4.Cu" signal "L05_VCC1")
		(12 "In5.Cu" signal "L06_VCC2")
		(14 "In6.Cu" signal "L07_GND3")
		(16 "In7.Cu" signal "L08_SIG2")
		(18 "In8.Cu" signal "L09_GND4")
		(2 "B.Cu" signal "BOTTOM")
		(9 "F.Adhes" user "F.Adhesive")
		(11 "B.Adhes" user "B.Adhesive")
		(13 "F.Paste" user "Package Geometry/Pastemask Top")
		(15 "B.Paste" user "Package Geometry/Pastemask Bottom")
		(5 "F.SilkS" user "Ref Des/Silkscreen Top")
		(7 "B.SilkS" user "Ref Des/Silkscreen Bottom")
		(1 "F.Mask" user "Board Geometry/Soldermask Top")
		(3 "B.Mask" user "Board Geometry/Soldermask Bottom")
		(17 "Dwgs.User" user "User.Drawings")
		(19 "Cmts.User" user "User.Comments")
		(21 "Eco1.User" user "User.Eco1")
		(23 "Eco2.User" user "User.Eco2")
		(25 "Edge.Cuts" user "Board Geometry/Outline")
		(27 "Margin" user)
		(31 "F.CrtYd" user "Package Geometry/Place Bound Top")
		(29 "B.CrtYd" user "Package Geometry/Place Bound Bottom")
		(35 "F.Fab" user "Ref Des/Assembly Top")
		(33 "B.Fab" user "Ref Des/Assembly Bottom")
	)
	(footprint ""
		(layer "F.Cu")
		(at 20.32 -31.75 180)
		(property "Reference" "R274"
			(at -2.794 -0.67437 0)
			(unlocked yes)
			(layer "F.SilkS")
			(effects
				(font
					(size 0.7874 0.5842)
					(thickness 0.1524)
				)
			)
		)
		(property "Value" "VAL*"
			(at 0.02032 2.13233 180)
			(unlocked yes)
			(layer "F.Fab")
			(hide yes)
			(effects
				(font
					(size 0.7874 0.5842)
					(thickness 0.1524)
				)
			)
		)
		(property "Device Type" "RESISTOR-G155-11000-01,100OHM,A"
			(at 0.008382 1.210564 180)
			(unlocked yes)
			(layer "F.Fab")
			(hide yes)
			(effects
				(font
					(size 0.7874 0.5842)
					(thickness 0.1524)
				)
			)
		)
		(property "User Part Number" "PARTNUM*"
			(at 0.02032 4.024884 180)
			(unlocked yes)
			(layer "Cmts.User")
			(hide yes)
			(effects
				(font
					(size 0.7874 0.5842)
					(thickness 0.1524)
				)
			)
		)
		(property "Tolerance" "TOL*"
			(at 0.044704 3.05435 180)
			(unlocked yes)
			(layer "Cmts.User")
			(hide yes)
			(effects
				(font
					(size 0.7874 0.5842)
					(thickness 0.1524)
				)
			)
		)
		(duplicate_pad_numbers_are_jumpers no)
		(fp_line
			(start 1.143 0.5588)
			(end 1.143 -0.5588)
			(stroke
				(width 0.1)
				(type default)
			)
			(layer "F.SilkS")
		)
		(fp_line
			(start 1.143 -0.5588)
			(end -1.143 -0.5588)
			(stroke
				(width 0.1)
				(type default)
			)
			(layer "F.SilkS")
		)
		(fp_line
			(start -1.143 0.5588)
			(end 1.143 0.5588)
			(stroke
				(width 0.1)
				(type default)
			)
			(layer "F.SilkS")
		)
		(fp_line
			(start -1.143 -0.5588)
			(end -1.143 0.5588)
			(stroke
				(width 0.1)
				(type default)
			)
			(layer "F.SilkS")
		)
		(fp_poly
			(pts
				(xy -1.143 0.5588) (xy 1.143 0.5588) (xy 1.143 -0.5588) (xy -1.143 -0.5588)
			)
			(stroke
				(width 0)
				(type default)
			)
			(fill no)
			(layer "F.CrtYd")
		)
		(fp_line
			(start 0.508 0.3048)
			(end 0.508 -0.3048)
			(stroke
				(width 0.1)
				(type default)
			)
			(layer "F.Fab")
		)
		(fp_line
			(start 0.508 -0.3048)
			(end -0.508 -0.3048)
			(stroke
				(width 0.1)
				(type default)
			)
			(layer "F.Fab")
		)
		(fp_line
			(start -0.508 0.3048)
			(end 0.508 0.3048)
			(stroke
				(width 0.1)
				(type default)
			)
			(layer "F.Fab")
		)
		(fp_line
			(start -0.508 -0.3048)
			(end -0.508 0.3048)
			(stroke
				(width 0.1)
				(type default)
			)
			(layer "F.Fab")
		)
		(pad "1" smd rect
			(at -0.5334 0 180)
			(size 0.7112 0.6096)
			(layers "F.Cu" "F.Mask" "F.Paste")
			(net "FPGA_OUT_SMA2_LED_GREEN_N")
		)
		(pad "2" smd rect
			(at 0.5334 0 180)
			(size 0.7112 0.6096)
			(layers "F.Cu" "F.Mask" "F.Paste")
			(net "UNNAMED_14_LED4PV14_I266_4")
		)
		(zone
			(layer "F.Cu")
			(hatch none 0.5)
			(connect_pads
				(clearance 0)
			)
			(min_thickness 0.25)
			(keepout
				(tracks not_allowed)
				(vias allowed)
				(pads allowed)
				(copperpour not_allowed)
				(footprints allowed)
			)
			(placement
				(enabled no)
				(sheetname "")
			)
			(fill
				(thermal_gap 0.5)
				(thermal_bridge_width 0.5)
				(island_removal_mode 0)
			)
			(polygon
				(pts
					(xy 20.3962 -32.0548) (xy 20.2438 -32.0548) (xy 20.2438 -31.4452) (xy 20.3962 -31.4452)
				)
			)
		)
		(zone
			(layer "F.Cu")
			(hatch none 0.5)
			(connect_pads
				(clearance 0)
			)
			(min_thickness 0.25)
			(keepout
				(tracks allowed)
				(vias not_allowed)
				(pads allowed)
				(copperpour not_allowed)
				(footprints allowed)
			)
			(placement
				(enabled no)
				(sheetname "")
			)
			(fill
				(thermal_gap 0.5)
				(thermal_bridge_width 0.5)
				(island_removal_mode 0)
			)
			(polygon
				(pts
					(xy 20.3962 -32.0548) (xy 20.2438 -32.0548) (xy 20.2438 -31.4452) (xy 20.3962 -31.4452)
				)
			)
		)
	)
	(footprint ""
		(layer "F.Cu")
		(at 145.8214 -93.1418 180)
		(property "Reference" "R8"
			(at 0.2794 -8.72617 0)
			(unlocked yes)
			(layer "F.SilkS")
			(effects
				(font
					(size 0.7874 0.5842)
					(thickness 0.1524)
				)
			)
		)
		(property "Value" "VAL*"
			(at 0.02032 2.13233 180)
			(unlocked yes)
			(layer "F.Fab")
			(hide yes)
			(effects
				(font
					(size 0.7874 0.5842)
					(thickness 0.1524)
				)
			)
		)
		(property "Device Type" "RESISTOR-G155-100R0-J0,0OHM,-"
			(at 0.008382 1.210564 180)
			(unlocked yes)
			(layer "F.Fab")
			(hide yes)
			(effects
				(font
					(size 0.7874 0.5842)
					(thickness 0.1524)
				)
			)
		)
		(property "User Part Number" "PARTNUM*"
			(at 0.02032 4.024884 180)
			(unlocked yes)
			(layer "Cmts.User")
			(hide yes)
			(effects
				(font
					(size 0.7874 0.5842)
					(thickness 0.1524)
				)
			)
		)
		(property "Tolerance" "TOL*"
			(at 0.044704 3.05435 180)
			(unlocked yes)
			(layer "Cmts.User")
			(hide yes)
			(effects
				(font
					(size 0.7874 0.5842)
					(thickness 0.1524)
				)
			)
		)
		(duplicate_pad_numbers_are_jumpers no)
		(fp_line
			(start 1.143 0.5588)
			(end 1.143 -0.5588)
			(stroke
				(width 0.1)
				(type default)
			)
			(layer "F.SilkS")
		)
		(fp_line
			(start 1.143 -0.5588)
			(end -1.143 -0.5588)
			(stroke
				(width 0.1)
				(type default)
			)
			(layer "F.SilkS")
		)
		(fp_line
			(start -1.143 0.5588)
			(end 1.143 0.5588)
			(stroke
				(width 0.1)
				(type default)
			)
			(layer "F.SilkS")
		)
		(fp_line
			(start -1.143 -0.5588)
			(end -1.143 0.5588)
			(stroke
				(width 0.1)
				(type default)
			)
			(layer "F.SilkS")
		)
		(fp_rect
			(start 1.143 -0.5588)
			(end -1.143 0.5588)
			(stroke
				(width 0)
				(type default)
			)
			(fill no)
			(layer "F.CrtYd")
		)
		(fp_line
			(start 0.508 0.3048)
			(end 0.508 -0.3048)
			(stroke
				(width 0.1)
				(type default)
			)
			(layer "F.Fab")
		)
		(fp_line
			(start 0.508 -0.3048)
			(end -0.508 -0.3048)
			(stroke
				(width 0.1)
				(type default)
			)
			(layer "F.Fab")
		)
		(fp_line
			(start -0.508 0.3048)
			(end 0.508 0.3048)
			(stroke
				(width 0.1)
				(type default)
			)
			(layer "F.Fab")
		)
		(fp_line
			(start -0.508 -0.3048)
			(end -0.508 0.3048)
			(stroke
				(width 0.1)
				(type default)
			)
			(layer "F.Fab")
		)
		(pad "1" smd rect
			(at -0.5334 0 180)
			(size 0.7112 0.6096)
			(layers "F.Cu" "F.Mask" "F.Paste")
			(net "SG")
		)
		(pad "2" smd rect
			(at 0.5334 0 180)
			(size 0.7112 0.6096)
			(layers "F.Cu" "F.Mask" "F.Paste")
			(net "UNNAMED_15_MP5022CGQVZQFN22_I21")
		)
		(zone
			(layer "F.Cu")
			(hatch none 0.5)
			(connect_pads
				(clearance 0)
			)
			(min_thickness 0.25)
			(keepout
				(tracks allowed)
				(vias not_allowed)
				(pads allowed)
				(copperpour not_allowed)
				(footprints allowed)
			)
			(placement
				(enabled no)
				(sheetname "")
			)
			(fill
				(thermal_gap 0.5)
				(thermal_bridge_width 0.5)
				(island_removal_mode 0)
			)
			(polygon
				(pts
					(xy 145.7452 -92.837) (xy 145.8976 -92.837) (xy 145.8976 -93.4466) (xy 145.7452 -93.4466)
				)
			)
		)
	)
	(footprint ""
		(layer "F.Cu")
		(at 24.8412 -99.5172)
		(property "Reference" "TP42"
			(at 0.72517 -1.2446 90)
			(unlocked yes)
			(layer "F.SilkS")
			(effects
				(font
					(size 0.7874 0.5842)
					(thickness 0.1524)
				)
				(justify left)
			)
		)
		(property "Value" ""
			(at 0 0 0)
			(layer "F.Fab")
			(effects
				(font
					(size 1.27 1.27)
				)
			)
		)
		(property "Device Type" "TP_PIONT-TP010CT020B030_PTH-TPA"
			(at -1.341882 0.996696 0)
			(unlocked yes)
			(layer "F.Fab")
			(hide yes)
			(effects
				(font
					(size 0.7874 0.5842)
					(thickness 0.000001)
				)
				(justify left)
			)
		)
		(duplicate_pad_numbers_are_jumpers no)
		(fp_poly
			(pts
				(arc
					(start 0.889 0)
					(mid -0.889 0)
					(end 0.889 0)
				)
			)
			(stroke
				(width 0)
				(type default)
			)
			(fill no)
			(layer "B.CrtYd")
		)
		(fp_poly
			(pts
				(arc
					(start 0.889 0)
					(mid -0.889 0)
					(end 0.889 0)
				)
			)
			(stroke
				(width 0)
				(type default)
			)
			(fill no)
			(layer "F.CrtYd")
		)
		(pad "1" thru_hole circle
			(at 0 0)
			(size 0.508 0.508)
			(drill 0.254)
			(layers "*.Cu" "*.Mask")
			(remove_unused_layers no)
			(net "XP12R0V_IN")
			(clearance 0.1016)
			(padstack
				(mode front_inner_back)
				(layer "Inner"
					(shape circle)
					(size 0.508 0.508)
					(clearance 0.1016)
				)
				(layer "B.Cu"
					(shape circle)
					(size 0.762 0.762)
					(clearance -0.0254)
				)
			)
		)
	)
	(footprint ""
		(layer "F.Cu")
		(at 92.0242 -97.9678 90)
		(property "Reference" "R17"
			(at -0.0508 1.36017 90)
			(unlocked yes)
			(layer "F.SilkS")
			(effects
				(font
					(size 0.7874 0.5842)
					(thickness 0.1524)
				)
			)
		)
		(property "Value" "VAL*"
			(at 0.02032 2.13233 90)
			(unlocked yes)
			(layer "F.Fab")
			(hide yes)
			(effects
				(font
					(size 0.7874 0.5842)
					(thickness 0.1524)
				)
			)
		)
		(property "Tolerance" "TOL*"
			(at 0.044704 3.05435 90)
			(unlocked yes)
			(layer "Cmts.User")
			(hide yes)
			(effects
				(font
					(size 0.7874 0.5842)
					(thickness 0.1524)
				)
			)
		)
		(property "User Part Number" "PARTNUM*"
			(at 0.02032 4.024884 90)
			(unlocked yes)
			(layer "Cmts.User")
			(hide yes)
			(effects
				(font
					(size 0.7874 0.5842)
					(thickness 0.1524)
				)
			)
		)
		(property "Device Type" "RESISTOR-G155-120R0-01,20OHM,1%"
			(at 0.008382 1.210564 90)
			(unlocked yes)
			(layer "F.Fab")
			(hide yes)
			(effects
				(font
					(size 0.7874 0.5842)
					(thickness 0.1524)
				)
			)
		)
		(duplicate_pad_numbers_are_jumpers no)
		(fp_line
			(start 1.143 -0.5588)
			(end -1.143 -0.5588)
			(stroke
				(width 0.1)
				(type default)
			)
			(layer "F.SilkS")
		)
		(fp_line
			(start -1.143 -0.5588)
			(end -1.143 0.5588)
			(stroke
				(width 0.1)
				(type default)
			)
			(layer "F.SilkS")
		)
		(fp_line
			(start 1.143 0.5588)
			(end 1.143 -0.5588)
			(stroke
				(width 0.1)
				(type default)
			)
			(layer "F.SilkS")
		)
		(fp_line
			(start -1.143 0.5588)
			(end 1.143 0.5588)
			(stroke
				(width 0.1)
				(type default)
			)
			(layer "F.SilkS")
		)
		(fp_rect
			(start -1.143 -0.5588)
			(end 1.143 0.5588)
			(stroke
				(width 0)
				(type default)
			)
			(fill no)
			(layer "F.CrtYd")
		)
		(fp_line
			(start 0.508 -0.3048)
			(end -0.508 -0.3048)
			(stroke
				(width 0.1)
				(type default)
			)
			(layer "F.Fab")
		)
		(fp_line
			(start -0.508 -0.3048)
			(end -0.508 0.3048)
			(stroke
				(width 0.1)
				(type default)
			)
			(layer "F.Fab")
		)
		(fp_line
			(start 0.508 0.3048)
			(end 0.508 -0.3048)
			(stroke
				(width 0.1)
				(type default)
			)
			(layer "F.Fab")
		)
		(fp_line
			(start -0.508 0.3048)
			(end 0.508 0.3048)
			(stroke
				(width 0.1)
				(type default)
			)
			(layer "F.Fab")
		)
		(pad "1" smd rect
			(at -0.5334 0 90)
			(size 0.7112 0.6096)
			(layers "F.Cu" "F.Mask" "F.Paste")
			(net "XP3R3V")
		)
		(pad "2" smd rect
			(at 0.5334 0 90)
			(size 0.7112 0.6096)
			(layers "F.Cu" "F.Mask" "F.Paste")
			(net "UNNAMED_517_CAPACITOR_I30_1")
		)
		(zone
			(layer "F.Cu")
			(hatch none 0.5)
			(connect_pads
				(clearance 0)
			)
			(min_thickness 0.25)
			(keepout
				(tracks allowed)
				(vias not_allowed)
				(pads allowed)
				(copperpour not_allowed)
				(footprints allowed)
			)
			(placement
				(enabled no)
				(sheetname "")
			)
			(fill
				(thermal_gap 0.5)
				(thermal_bridge_width 0.5)
				(island_removal_mode 0)
			)
			(polygon
				(pts
					(xy 91.7194 -97.8916) (xy 92.329 -97.8916) (xy 92.329 -98.044) (xy 91.7194 -98.044)
				)
			)
		)
	)
	(footprint ""
		(layer "F.Cu")
		(at 82.7786 -52.959 -90)
		(property "Reference" "R277"
			(at 13.589 0.96393 90)
			(unlocked yes)
			(layer "F.SilkS")
			(effects
				(font
					(size 0.7874 0.5842)
					(thickness 0.1524)
				)
			)
		)
		(property "Value" "VAL*"
			(at 0.02032 2.13233 270)
			(unlocked yes)
			(layer "F.Fab")
			(hide yes)
			(effects
				(font
					(size 0.7874 0.5842)
					(thickness 0.1524)
				)
			)
		)
		(property "Tolerance" "TOL*"
			(at 0.044704 3.05435 270)
			(unlocked yes)
			(layer "Cmts.User")
			(hide yes)
			(effects
				(font
					(size 0.7874 0.5842)
					(thickness 0.1524)
				)
			)
		)
		(property "User Part Number" "PARTNUM*"
			(at 0.02032 4.024884 270)
			(unlocked yes)
			(layer "Cmts.User")
			(hide yes)
			(effects
				(font
					(size 0.7874 0.5842)
					(thickness 0.1524)
				)
			)
		)
		(property "Device Type" "RESISTOR-G155-11000-01,100OHM,A"
			(at 0.008382 1.210564 270)
			(unlocked yes)
			(layer "F.Fab")
			(hide yes)
			(effects
				(font
					(size 0.7874 0.5842)
					(thickness 0.1524)
				)
			)
		)
		(duplicate_pad_numbers_are_jumpers no)
		(fp_line
			(start -1.143 0.5588)
			(end 1.143 0.5588)
			(stroke
				(width 0.1)
				(type default)
			)
			(layer "F.SilkS")
		)
		(fp_line
			(start 1.143 0.5588)
			(end 1.143 -0.5588)
			(stroke
				(width 0.1)
				(type default)
			)
			(layer "F.SilkS")
		)
		(fp_line
			(start -1.143 -0.5588)
			(end -1.143 0.5588)
			(stroke
				(width 0.1)
				(type default)
			)
			(layer "F.SilkS")
		)
		(fp_line
			(start 1.143 -0.5588)
			(end -1.143 -0.5588)
			(stroke
				(width 0.1)
				(type default)
			)
			(layer "F.SilkS")
		)
		(fp_rect
			(start 1.143 0.5588)
			(end -1.143 -0.5588)
			(stroke
				(width 0)
				(type default)
			)
			(fill no)
			(layer "F.CrtYd")
		)
		(fp_line
			(start -0.508 0.3048)
			(end 0.508 0.3048)
			(stroke
				(width 0.1)
				(type default)
			)
			(layer "F.Fab")
		)
		(fp_line
			(start 0.508 0.3048)
			(end 0.508 -0.3048)
			(stroke
				(width 0.1)
				(type default)
			)
			(layer "F.Fab")
		)
		(fp_line
			(start -0.508 -0.3048)
			(end -0.508 0.3048)
			(stroke
				(width 0.1)
				(type default)
			)
			(layer "F.Fab")
		)
		(fp_line
			(start 0.508 -0.3048)
			(end -0.508 -0.3048)
			(stroke
				(width 0.1)
				(type default)
			)
			(layer "F.Fab")
		)
		(pad "1" smd rect
			(at -0.5334 0 270)
			(size 0.7112 0.6096)
			(layers "F.Cu" "F.Mask" "F.Paste")
			(net "FPGA_OUT_MAC_PPS_IN1P")
		)
		(pad "2" smd rect
			(at 0.5334 0 270)
			(size 0.7112 0.6096)
			(layers "F.Cu" "F.Mask" "F.Paste")
			(net "FPGA_OUT_MAC_PPS_IN1N")
		)
		(zone
			(layer "F.Cu")
			(hatch none 0.5)
			(connect_pads
				(clearance 0)
			)
			(min_thickness 0.25)
			(keepout
				(tracks allowed)
				(vias not_allowed)
				(pads allowed)
				(copperpour not_allowed)
				(footprints allowed)
			)
			(placement
				(enabled no)
				(sheetname "")
			)
			(fill
				(thermal_gap 0.5)
				(thermal_bridge_width 0.5)
				(island_removal_mode 0)
			)
			(polygon
				(pts
					(xy 82.4738 -52.8828) (xy 83.0834 -52.8828) (xy 83.0834 -53.0352) (xy 82.4738 -53.0352)
				)
			)
		)
	)
	(footprint ""
		(layer "F.Cu")
		(at 103.632 -87.63 90)
		(property "Reference" "R465"
			(at -1.397 4.61137 90)
			(unlocked yes)
			(layer "F.SilkS")
			(effects
				(font
					(size 0.7874 0.5842)
					(thickness 0.1524)
				)
			)
		)
		(property "Value" "VAL*"
			(at 0.02032 2.13233 90)
			(unlocked yes)
			(layer "F.Fab")
			(hide yes)
			(effects
				(font
					(size 0.7874 0.5842)
					(thickness 0.1524)
				)
			)
		)
		(property "Tolerance" "TOL*"
			(at 0.044704 3.05435 90)
			(unlocked yes)
			(layer "Cmts.User")
			(hide yes)
			(effects
				(font
					(size 0.7874 0.5842)
					(thickness 0.1524)
				)
			)
		)
		(property "User Part Number" "PARTNUM*"
			(at 0.02032 4.024884 90)
			(unlocked yes)
			(layer "Cmts.User")
			(hide yes)
			(effects
				(font
					(size 0.7874 0.5842)
					(thickness 0.1524)
				)
			)
		)
		(property "Device Type" "RESISTOR-G155-100R0-J0,0OHM,-"
			(at 0.008382 1.210564 90)
			(unlocked yes)
			(layer "F.Fab")
			(hide yes)
			(effects
				(font
					(size 0.7874 0.5842)
					(thickness 0.1524)
				)
			)
		)
		(duplicate_pad_numbers_are_jumpers no)
		(fp_line
			(start 1.143 -0.5588)
			(end -1.143 -0.5588)
			(stroke
				(width 0.1)
				(type default)
			)
			(layer "F.SilkS")
		)
		(fp_line
			(start -1.143 -0.5588)
			(end -1.143 0.5588)
			(stroke
				(width 0.1)
				(type default)
			)
			(layer "F.SilkS")
		)
		(fp_line
			(start 1.143 0.5588)
			(end 1.143 -0.5588)
			(stroke
				(width 0.1)
				(type default)
			)
			(layer "F.SilkS")
		)
		(fp_line
			(start -1.143 0.5588)
			(end 1.143 0.5588)
			(stroke
				(width 0.1)
				(type default)
			)
			(layer "F.SilkS")
		)
		(fp_poly
			(pts
				(xy -1.143 0.5588) (xy 1.143 0.5588) (xy 1.143 -0.5588) (xy -1.143 -0.5588)
			)
			(stroke
				(width 0)
				(type default)
			)
			(fill no)
			(layer "F.CrtYd")
		)
		(fp_line
			(start 0.508 -0.3048)
			(end -0.508 -0.3048)
			(stroke
				(width 0.1)
				(type default)
			)
			(layer "F.Fab")
		)
		(fp_line
			(start -0.508 -0.3048)
			(end -0.508 0.3048)
			(stroke
				(width 0.1)
				(type default)
			)
			(layer "F.Fab")
		)
		(fp_line
			(start 0.508 0.3048)
			(end 0.508 -0.3048)
			(stroke
				(width 0.1)
				(type default)
			)
			(layer "F.Fab")
		)
		(fp_line
			(start -0.508 0.3048)
			(end 0.508 0.3048)
			(stroke
				(width 0.1)
				(type default)
			)
			(layer "F.Fab")
		)
		(pad "1" smd rect
			(at -0.5334 0 90)
			(size 0.7112 0.6096)
			(layers "F.Cu" "F.Mask" "F.Paste")
			(net "FPGA_FLASH_DQ3")
		)
		(pad "2" smd rect
			(at 0.5334 0 90)
			(size 0.7112 0.6096)
			(layers "F.Cu" "F.Mask" "F.Paste")
			(net "FLASH_DQ3")
		)
		(zone
			(layer "F.Cu")
			(hatch none 0.5)
			(connect_pads
				(clearance 0)
			)
			(min_thickness 0.25)
			(keepout
				(tracks not_allowed)
				(vias allowed)
				(pads allowed)
				(copperpour not_allowed)
				(footprints allowed)
			)
			(placement
				(enabled no)
				(sheetname "")
			)
			(fill
				(thermal_gap 0.5)
				(thermal_bridge_width 0.5)
				(island_removal_mode 0)
			)
			(polygon
				(pts
					(xy 103.9368 -87.5538) (xy 103.9368 -87.7062) (xy 103.3272 -87.7062) (xy 103.3272 -87.5538)
				)
			)
		)
		(zone
			(layer "F.Cu")
			(hatch none 0.5)
			(connect_pads
				(clearance 0)
			)
			(min_thickness 0.25)
			(keepout
				(tracks allowed)
				(vias not_allowed)
				(pads allowed)
				(copperpour not_allowed)
				(footprints allowed)
			)
			(placement
				(enabled no)
				(sheetname "")
			)
			(fill
				(thermal_gap 0.5)
				(thermal_bridge_width 0.5)
				(island_removal_mode 0)
			)
			(polygon
				(pts
					(xy 103.9368 -87.5538) (xy 103.9368 -87.7062) (xy 103.3272 -87.7062) (xy 103.3272 -87.5538)
				)
			)
		)
	)
)
